(kicad_pcb
	(version 20260206)
	(generator "pcbnew")
	(generator_version "10.0")
	(general
		(thickness 1.6)
		(legacy_teardrops no)
	)
	(paper "A4")
	(title_block
		(title "ptb — Lightning_PTB_BRD.brd")
		(comment 1 "Lightning (Wiwynn / Facebook NVMe JBOF) / footprint 15 of 61 (CN4), pads 1-54 of 54")
	)
	(layers
		(0 "F.Cu" signal "TOP")
		(4 "In1.Cu" signal "L2GND")
		(6 "In2.Cu" signal "L3VCC")
		(2 "B.Cu" signal "BOTTOM")
		(9 "F.Adhes" user "F.Adhesive")
		(11 "B.Adhes" user "B.Adhesive")
		(13 "F.Paste" user "Package Geometry/Pastemask Top")
		(15 "B.Paste" user "Package Geometry/Pastemask Bottom")
		(5 "F.SilkS" user "Ref Des/Silkscreen Top")
		(7 "B.SilkS" user "Ref Des/Silkscreen Bottom")
		(1 "F.Mask" user "Board Geometry/Soldermask Top")
		(3 "B.Mask" user "Board Geometry/Soldermask Bottom")
		(17 "Dwgs.User" user "User.Drawings")
		(19 "Cmts.User" user "User.Comments")
		(21 "Eco1.User" user "User.Eco1")
		(23 "Eco2.User" user "User.Eco2")
		(25 "Edge.Cuts" user "Board Geometry/Outline")
		(27 "Margin" user)
		(31 "F.CrtYd" user "Package Geometry/Place Bound Top")
		(29 "B.CrtYd" user "Package Geometry/Place Bound Bottom")
		(35 "F.Fab" user "Ref Des/Assembly Top")
		(33 "B.Fab" user "Ref Des/Assembly Bottom")
	)
	(footprint ""
		(layer "F.Cu")
		(at 152.580086 -56.999886 90)
		(property "Reference" "CN4"
			(at 0 0 90)
			(layer "F.SilkS")
			(hide yes)
			(effects
				(font
					(size 1.27 1.27)
				)
			)
		)
		(property "Value" "FCI-CONN52-4R-GP"
			(at -28.321 -4.0132 90)
			(unlocked yes)
			(layer "F.Fab")
			(hide yes)
			(effects
				(font
					(size 1.016 1.016)
					(thickness 0.1524)
				)
			)
		)
		(property "Device Type" "51939-689LF"
			(at -28.321 -5.5372 90)
			(unlocked yes)
			(layer "F.Fab")
			(hide yes)
			(effects
				(font
					(size 1.016 1.016)
					(thickness 0.1524)
				)
			)
		)
		(duplicate_pad_numbers_are_jumpers no)
		(pad "" np_thru_hole circle
			(at -22.225 0 90)
			(size 0.254 0.254)
			(drill 4.0132)
			(layers "*.Cu" "*.Mask")
			(clearance 2.2352)
			(thermal_gap 2.2352)
		)
		(pad "" np_thru_hole circle
			(at 22.225 0 90)
			(size 0.254 0.254)
			(drill 4.0132)
			(layers "*.Cu" "*.Mask")
			(clearance 2.2352)
			(thermal_gap 2.2352)
		)
		(pad "A1" thru_hole circle
			(at -5.08 0 90)
			(size 1.4478 1.4478)
			(drill 1.0414)
			(layers "*.Cu" "*.Mask")
			(remove_unused_layers no)
			(net "I2C_C_BUF_SDA_CONN")
			(clearance 0.1524)
			(thermal_gap 0.1524)
		)
		(pad "A2" thru_hole circle
			(at -2.54 0 90)
			(size 1.4478 1.4478)
			(drill 1.0414)
			(layers "*.Cu" "*.Mask")
			(remove_unused_layers no)
			(net "GND")
			(clearance 0.1524)
			(thermal_gap 0.1524)
		)
		(pad "A3" thru_hole circle
			(at 0 0 90)
			(size 1.4478 1.4478)
			(drill 1.0414)
			(layers "*.Cu" "*.Mask")
			(remove_unused_layers no)
			(net "I2C_C_BUF_SCL_CONN")
			(clearance 0.1524)
			(thermal_gap 0.1524)
		)
		(pad "A4" thru_hole circle
			(at 2.54 0 90)
			(size 1.4478 1.4478)
			(drill 1.0414)
			(layers "*.Cu" "*.Mask")
			(remove_unused_layers no)
			(net "GND")
			(clearance 0.1524)
			(thermal_gap 0.1524)
		)
		(pad "A5" thru_hole circle
			(at 5.08 0 90)
			(size 1.4478 1.4478)
			(drill 1.0414)
			(layers "*.Cu" "*.Mask")
			(remove_unused_layers no)
			(net "PWM_EXP_B_OUT")
			(clearance 0.1524)
			(thermal_gap 0.1524)
		)
		(pad "B1" thru_hole circle
			(at -5.08 -2.54 90)
			(size 1.4478 1.4478)
			(drill 1.0414)
			(layers "*.Cu" "*.Mask")
			(remove_unused_layers no)
			(net "GND")
			(clearance 0.1524)
			(thermal_gap 0.1524)
		)
		(pad "B2" thru_hole circle
			(at -2.54 -2.54 90)
			(size 1.4478 1.4478)
			(drill 1.0414)
			(layers "*.Cu" "*.Mask")
			(remove_unused_layers no)
			(net "PWM_EXP_A_OUT")
			(clearance 0.1524)
			(thermal_gap 0.1524)
		)
		(pad "B3" thru_hole circle
			(at 0 -2.54 90)
			(size 1.4478 1.4478)
			(drill 1.0414)
			(layers "*.Cu" "*.Mask")
			(remove_unused_layers no)
			(net "GND")
			(clearance 0.1524)
			(thermal_gap 0.1524)
		)
		(pad "B4" thru_hole circle
			(at 2.54 -2.54 90)
			(size 1.4478 1.4478)
			(drill 1.0414)
			(layers "*.Cu" "*.Mask")
			(remove_unused_layers no)
			(net "SELF_1B&2B_HB")
			(clearance 0.1524)
			(thermal_gap 0.1524)
		)
		(pad "B5" thru_hole circle
			(at 5.08 -2.54 90)
			(size 1.4478 1.4478)
			(drill 1.0414)
			(layers "*.Cu" "*.Mask")
			(remove_unused_layers no)
			(net "GND")
			(clearance 0.1524)
			(thermal_gap 0.1524)
		)
		(pad "C1" thru_hole circle
			(at -5.08 -5.08 90)
			(size 1.4478 1.4478)
			(drill 1.0414)
			(layers "*.Cu" "*.Mask")
			(remove_unused_layers no)
			(net "TPS2490_EN1")
			(clearance 0.1524)
			(thermal_gap 0.1524)
		)
		(pad "C2" thru_hole circle
			(at -2.54 -5.08 90)
			(size 1.4478 1.4478)
			(drill 1.0414)
			(layers "*.Cu" "*.Mask")
			(remove_unused_layers no)
			(net "TPS2490_EN2")
			(clearance 0.1524)
			(thermal_gap 0.1524)
		)
		(pad "C3" thru_hole circle
			(at 0 -5.08 90)
			(size 1.4478 1.4478)
			(drill 1.0414)
			(layers "*.Cu" "*.Mask")
			(remove_unused_layers no)
			(net "SELF_1A&2A_HB")
			(clearance 0.1524)
			(thermal_gap 0.1524)
		)
		(pad "C4" thru_hole circle
			(at 2.54 -5.08 90)
			(size 1.4478 1.4478)
			(drill 1.0414)
			(layers "*.Cu" "*.Mask")
			(remove_unused_layers no)
			(net "PEER_1A&2A_HB")
			(clearance 0.1524)
			(thermal_gap 0.1524)
		)
		(pad "C5" thru_hole circle
			(at 5.08 -5.08 90)
			(size 1.4478 1.4478)
			(drill 1.0414)
			(layers "*.Cu" "*.Mask")
			(remove_unused_layers no)
			(net "PEER_1B&2B_HB")
			(clearance 0.1524)
			(thermal_gap 0.1524)
		)
		(pad "D1" thru_hole circle
			(at -5.08 -7.62 90)
			(size 1.4478 1.4478)
			(drill 1.0414)
			(layers "*.Cu" "*.Mask")
			(remove_unused_layers no)
			(net "PEER_TRAY_PRESENT")
			(clearance 0.1524)
			(thermal_gap 0.1524)
		)
		(pad "D2" thru_hole circle
			(at -2.54 -7.62 90)
			(size 1.4478 1.4478)
			(drill 1.0414)
			(layers "*.Cu" "*.Mask")
			(remove_unused_layers no)
			(net "TRAY_ID")
			(clearance 0.1524)
			(thermal_gap 0.1524)
		)
		(pad "D3" thru_hole circle
			(at 0 -7.62 90)
			(size 1.4478 1.4478)
			(drill 1.0414)
			(layers "*.Cu" "*.Mask")
			(remove_unused_layers no)
			(net "FCB_HW_REV")
			(clearance 0.1524)
			(thermal_gap 0.1524)
		)
		(pad "D4" thru_hole circle
			(at 2.54 -7.62 90)
			(size 1.4478 1.4478)
			(drill 1.0414)
			(layers "*.Cu" "*.Mask")
			(remove_unused_layers no)
			(net "SD_LATCH_RELEASE")
			(clearance 0.1524)
			(thermal_gap 0.1524)
		)
		(pad "D5" thru_hole circle
			(at 5.08 -7.62 90)
			(size 1.4478 1.4478)
			(drill 1.0414)
			(layers "*.Cu" "*.Mask")
			(remove_unused_layers no)
			(net "SELF_TRAY_PRESENT")
			(clearance 0.1524)
			(thermal_gap 0.1524)
		)
		(pad "P1_1" thru_hole circle
			(at -15.88008 0 90)
			(size 1.4478 1.4478)
			(drill 1.0414)
			(layers "*.Cu" "*.Mask")
			(remove_unused_layers no)
			(net "P12V")
			(clearance 0.1524)
			(thermal_gap 0.1524)
		)
		(pad "P1_2" thru_hole circle
			(at -15.88008 -2.54 90)
			(size 1.4478 1.4478)
			(drill 1.0414)
			(layers "*.Cu" "*.Mask")
			(remove_unused_layers no)
			(net "P12V")
			(clearance 0.1524)
			(thermal_gap 0.1524)
		)
		(pad "P1_3" thru_hole circle
			(at -15.88008 -5.08 90)
			(size 1.4478 1.4478)
			(drill 1.0414)
			(layers "*.Cu" "*.Mask")
			(remove_unused_layers no)
			(net "P12V")
			(clearance 0.1524)
			(thermal_gap 0.1524)
		)
		(pad "P1_4" thru_hole circle
			(at -15.88008 -7.62 90)
			(size 1.4478 1.4478)
			(drill 1.0414)
			(layers "*.Cu" "*.Mask")
			(remove_unused_layers no)
			(net "P12V")
			(clearance 0.1524)
			(thermal_gap 0.1524)
		)
		(pad "P1_5" thru_hole circle
			(at -13.34008 0 90)
			(size 1.4478 1.4478)
			(drill 1.0414)
			(layers "*.Cu" "*.Mask")
			(remove_unused_layers no)
			(net "P12V")
			(clearance 0.1524)
			(thermal_gap 0.1524)
		)
		(pad "P1_6" thru_hole circle
			(at -13.34008 -2.54 90)
			(size 1.4478 1.4478)
			(drill 1.0414)
			(layers "*.Cu" "*.Mask")
			(remove_unused_layers no)
			(net "P12V")
			(clearance 0.1524)
			(thermal_gap 0.1524)
		)
		(pad "P1_7" thru_hole circle
			(at -13.34008 -5.08 90)
			(size 1.4478 1.4478)
			(drill 1.0414)
			(layers "*.Cu" "*.Mask")
			(remove_unused_layers no)
			(net "P12V")
			(clearance 0.1524)
			(thermal_gap 0.1524)
		)
		(pad "P1_8" thru_hole circle
			(at -13.34008 -7.62 90)
			(size 1.4478 1.4478)
			(drill 1.0414)
			(layers "*.Cu" "*.Mask")
			(remove_unused_layers no)
			(net "P12V")
			(clearance 0.1524)
			(thermal_gap 0.1524)
		)
		(pad "P2_1" thru_hole circle
			(at -10.80008 0 90)
			(size 1.4478 1.4478)
			(drill 1.0414)
			(layers "*.Cu" "*.Mask")
			(remove_unused_layers no)
			(net "P12V")
			(clearance 0.1524)
			(thermal_gap 0.1524)
		)
		(pad "P2_2" thru_hole circle
			(at -10.80008 -2.54 90)
			(size 1.4478 1.4478)
			(drill 1.0414)
			(layers "*.Cu" "*.Mask")
			(remove_unused_layers no)
			(net "P12V")
			(clearance 0.1524)
			(thermal_gap 0.1524)
		)
		(pad "P2_3" thru_hole circle
			(at -10.80008 -5.08 90)
			(size 1.4478 1.4478)
			(drill 1.0414)
			(layers "*.Cu" "*.Mask")
			(remove_unused_layers no)
			(net "P12V")
			(clearance 0.1524)
			(thermal_gap 0.1524)
		)
		(pad "P2_4" thru_hole circle
			(at -10.80008 -7.62 90)
			(size 1.4478 1.4478)
			(drill 1.0414)
			(layers "*.Cu" "*.Mask")
			(remove_unused_layers no)
			(net "P12V")
			(clearance 0.1524)
			(thermal_gap 0.1524)
		)
		(pad "P2_5" thru_hole circle
			(at -8.26008 0 90)
			(size 1.4478 1.4478)
			(drill 1.0414)
			(layers "*.Cu" "*.Mask")
			(remove_unused_layers no)
			(net "P12V")
			(clearance 0.1524)
			(thermal_gap 0.1524)
		)
		(pad "P2_6" thru_hole circle
			(at -8.26008 -2.54 90)
			(size 1.4478 1.4478)
			(drill 1.0414)
			(layers "*.Cu" "*.Mask")
			(remove_unused_layers no)
			(net "P12V")
			(clearance 0.1524)
			(thermal_gap 0.1524)
		)
		(pad "P2_7" thru_hole circle
			(at -8.26008 -5.08 90)
			(size 1.4478 1.4478)
			(drill 1.0414)
			(layers "*.Cu" "*.Mask")
			(remove_unused_layers no)
			(net "P12V")
			(clearance 0.1524)
			(thermal_gap 0.1524)
		)
		(pad "P2_8" thru_hole circle
			(at -8.26008 -7.62 90)
			(size 1.4478 1.4478)
			(drill 1.0414)
			(layers "*.Cu" "*.Mask")
			(remove_unused_layers no)
			(net "P12V")
			(clearance 0.1524)
			(thermal_gap 0.1524)
		)
		(pad "P3_1" thru_hole circle
			(at 8.26008 0 90)
			(size 1.4478 1.4478)
			(drill 1.0414)
			(layers "*.Cu" "*.Mask")
			(remove_unused_layers no)
			(net "GND")
			(clearance 0.1524)
			(thermal_gap 0.1524)
		)
		(pad "P3_2" thru_hole circle
			(at 8.26008 -2.54 90)
			(size 1.4478 1.4478)
			(drill 1.0414)
			(layers "*.Cu" "*.Mask")
			(remove_unused_layers no)
			(net "GND")
			(clearance 0.1524)
			(thermal_gap 0.1524)
		)
		(pad "P3_3" thru_hole circle
			(at 8.26008 -5.08 90)
			(size 1.4478 1.4478)
			(drill 1.0414)
			(layers "*.Cu" "*.Mask")
			(remove_unused_layers no)
			(net "GND")
			(clearance 0.1524)
			(thermal_gap 0.1524)
		)
		(pad "P3_4" thru_hole circle
			(at 8.26008 -7.62 90)
			(size 1.4478 1.4478)
			(drill 1.0414)
			(layers "*.Cu" "*.Mask")
			(remove_unused_layers no)
			(net "GND")
			(clearance 0.1524)
			(thermal_gap 0.1524)
		)
		(pad "P3_5" thru_hole circle
			(at 10.80008 0 90)
			(size 1.4478 1.4478)
			(drill 1.0414)
			(layers "*.Cu" "*.Mask")
			(remove_unused_layers no)
			(net "GND")
			(clearance 0.1524)
			(thermal_gap 0.1524)
		)
		(pad "P3_6" thru_hole circle
			(at 10.80008 -2.54 90)
			(size 1.4478 1.4478)
			(drill 1.0414)
			(layers "*.Cu" "*.Mask")
			(remove_unused_layers no)
			(net "GND")
			(clearance 0.1524)
			(thermal_gap 0.1524)
		)
		(pad "P3_7" thru_hole circle
			(at 10.80008 -5.08 90)
			(size 1.4478 1.4478)
			(drill 1.0414)
			(layers "*.Cu" "*.Mask")
			(remove_unused_layers no)
			(net "GND")
			(clearance 0.1524)
			(thermal_gap 0.1524)
		)
		(pad "P3_8" thru_hole circle
			(at 10.80008 -7.62 90)
			(size 1.4478 1.4478)
			(drill 1.0414)
			(layers "*.Cu" "*.Mask")
			(remove_unused_layers no)
			(net "GND")
			(clearance 0.1524)
			(thermal_gap 0.1524)
		)
		(pad "P4_1" thru_hole circle
			(at 13.34008 0 90)
			(size 1.4478 1.4478)
			(drill 1.0414)
			(layers "*.Cu" "*.Mask")
			(remove_unused_layers no)
			(net "GND")
			(clearance 0.1524)
			(thermal_gap 0.1524)
		)
		(pad "P4_2" thru_hole circle
			(at 13.34008 -2.54 90)
			(size 1.4478 1.4478)
			(drill 1.0414)
			(layers "*.Cu" "*.Mask")
			(remove_unused_layers no)
			(net "GND")
			(clearance 0.1524)
			(thermal_gap 0.1524)
		)
		(pad "P4_3" thru_hole circle
			(at 13.34008 -5.08 90)
			(size 1.4478 1.4478)
			(drill 1.0414)
			(layers "*.Cu" "*.Mask")
			(remove_unused_layers no)
			(net "GND")
			(clearance 0.1524)
			(thermal_gap 0.1524)
		)
		(pad "P4_4" thru_hole circle
			(at 13.34008 -7.62 90)
			(size 1.4478 1.4478)
			(drill 1.0414)
			(layers "*.Cu" "*.Mask")
			(remove_unused_layers no)
			(net "GND")
			(clearance 0.1524)
			(thermal_gap 0.1524)
		)
		(pad "P4_5" thru_hole circle
			(at 15.88008 0 90)
			(size 1.4478 1.4478)
			(drill 1.0414)
			(layers "*.Cu" "*.Mask")
			(remove_unused_layers no)
			(net "GND")
			(clearance 0.1524)
			(thermal_gap 0.1524)
		)
		(pad "P4_6" thru_hole circle
			(at 15.88008 -2.54 90)
			(size 1.4478 1.4478)
			(drill 1.0414)
			(layers "*.Cu" "*.Mask")
			(remove_unused_layers no)
			(net "GND")
			(clearance 0.1524)
			(thermal_gap 0.1524)
		)
		(pad "P4_7" thru_hole circle
			(at 15.88008 -5.08 90)
			(size 1.4478 1.4478)
			(drill 1.0414)
			(layers "*.Cu" "*.Mask")
			(remove_unused_layers no)
			(net "GND")
			(clearance 0.1524)
			(thermal_gap 0.1524)
		)
		(pad "P4_8" thru_hole circle
			(at 15.88008 -7.62 90)
			(size 1.4478 1.4478)
			(drill 1.0414)
			(layers "*.Cu" "*.Mask")
			(remove_unused_layers no)
			(net "GND")
			(clearance 0.1524)
			(thermal_gap 0.1524)
		)
	)
)
